# BASEBOARD_FAB2 (Tioga Pass) — schematic netlist excerpt (pin names and nets, part order shuffled) for the footprints in the layout excerpt that follows; sources: Cadence DE-HDL packaged netlist, KiCad conversion of Wiwynn_Tioga_Pass_MB.brd

C5D55  CAP_A  22.0UF 4V 20% X6S  pkg 0603V  page 217 : A = PVDDQ_ABC ; B = GND
R25W31  120R2F-GP  1%  pkg RCL_GP  page 151 : \1\ = BMC_M_CS_N ; \2\ = P1V2_AUX_BMC
R8E5  RES  33.2 1% CHIP  pkg 0402  page 181 : A = FM_CTNR_PS_ON_R ; B = FM_CTNR_PS_ON

(kicad_pcb
	(version 20260206)
	(generator "pcbnew")
	(generator_version "10.0")
	(general
		(thickness 1.6)
		(legacy_teardrops no)
	)
	(paper "A4")
	(title_block
		(title "Wiwynn_Tioga_Pass_MB.brd")
		(comment 1 "Tioga Pass / footprints 971-973 of 4770")
	)
	(layers
		(0 "F.Cu" signal "TOP")
		(4 "In1.Cu" signal "L2GND")
		(6 "In2.Cu" signal "L3")
		(8 "In3.Cu" signal "L4GND")
		(10 "In4.Cu" signal "L5")
		(12 "In5.Cu" signal "L6GND")
		(14 "In6.Cu" signal "L7VCC")
		(16 "In7.Cu" signal "L8VCC")
		(18 "In8.Cu" signal "L9GND")
		(20 "In9.Cu" signal "L10")
		(22 "In10.Cu" signal "L11GND")
		(24 "In11.Cu" signal "L12")
		(26 "In12.Cu" signal "L13GND")
		(2 "B.Cu" signal "BOTTOM")
		(9 "F.Adhes" user "F.Adhesive")
		(11 "B.Adhes" user "B.Adhesive")
		(13 "F.Paste" user "Package Geometry/Pastemask Top")
		(15 "B.Paste" user "Package Geometry/Pastemask Bottom")
		(5 "F.SilkS" user "Ref Des/Silkscreen Top")
		(7 "B.SilkS" user "Ref Des/Silkscreen Bottom")
		(1 "F.Mask" user "Board Geometry/Soldermask Top")
		(3 "B.Mask" user "Board Geometry/Soldermask Bottom")
		(17 "Dwgs.User" user "User.Drawings")
		(19 "Cmts.User" user "User.Comments")
		(21 "Eco1.User" user "User.Eco1")
		(23 "Eco2.User" user "User.Eco2")
		(25 "Edge.Cuts" user "Board Geometry/Outline")
		(27 "Margin" user)
		(31 "F.CrtYd" user "Package Geometry/Place Bound Top")
		(29 "B.CrtYd" user "Package Geometry/Place Bound Bottom")
		(35 "F.Fab" user "Ref Des/Assembly Top")
		(33 "B.Fab" user "Ref Des/Assembly Bottom")
	)
	(footprint ""
		(layer "F.Cu")
		(at 441.119006 -43.568874 180)
		(property "Reference" "R25W31"
			(at 0 0 180)
			(layer "F.SilkS")
			(hide yes)
			(effects
				(font
					(size 1.27 1.27)
				)
			)
		)
		(property "Value" "*"
			(at 0.064008 -4.108196 180)
			(unlocked yes)
			(layer "F.Fab")
			(hide yes)
			(effects
				(font
					(size 1.27 1.016)
					(thickness 0.1524)
				)
			)
		)
		(property "Device Type" "120R2F-GP_RCL_GP-120R2F-GP,64.A"
			(at 0.064008 -5.632196 180)
			(unlocked yes)
			(layer "F.Fab")
			(hide yes)
			(effects
				(font
					(size 1.27 1.016)
					(thickness 0.1524)
				)
			)
		)
		(duplicate_pad_numbers_are_jumpers no)
		(fp_line
			(start 0.508 -0.9398)
			(end -0.508 -0.9398)
			(stroke
				(width 0.1524)
				(type default)
			)
			(layer "F.SilkS")
		)
		(fp_line
			(start -0.508 -0.9398)
			(end -0.508 0.9398)
			(stroke
				(width 0.1524)
				(type default)
			)
			(layer "F.SilkS")
		)
		(fp_rect
			(start -0.508 0.9398)
			(end 0.508 -0.9398)
			(stroke
				(width 0)
				(type default)
			)
			(fill no)
			(layer "F.CrtYd")
		)
		(fp_rect
			(start -0.508 0.9398)
			(end 0.508 -0.9398)
			(stroke
				(width 0)
				(type default)
			)
			(fill no)
			(layer "F.Fab")
		)
		(pad "1" smd custom
			(at 0 -0.4445 180)
			(size 0.1397 0.1397)
			(layers "F.Cu" "F.Mask" "F.Paste")
			(net "BMC_M_CS_N")
			(options
				(clearance outline)
				(anchor circle)
			)
			(primitives
				(gr_poly
					(pts
						(arc
							(start -0.1778 -0.2794)
							(mid -0.249642 -0.249642)
							(end -0.2794 -0.1778)
						)
						(arc
							(start -0.2794 0.1778)
							(mid -0.249642 0.249642)
							(end -0.1778 0.2794)
						)
						(arc
							(start 0.1778 0.2794)
							(mid 0.249642 0.249642)
							(end 0.2794 0.1778)
						)
						(arc
							(start 0.2794 -0.1778)
							(mid 0.249642 -0.249642)
							(end 0.1778 -0.2794)
						)
					)
					(width 0)
					(fill yes)
				)
			)
		)
		(pad "2" smd custom
			(at 0 0.4445 180)
			(size 0.1397 0.1397)
			(layers "F.Cu" "F.Mask" "F.Paste")
			(net "P1V2_AUX_BMC")
			(options
				(clearance outline)
				(anchor circle)
			)
			(primitives
				(gr_poly
					(pts
						(arc
							(start -0.1778 -0.2794)
							(mid -0.249642 -0.249642)
							(end -0.2794 -0.1778)
						)
						(arc
							(start -0.2794 0.1778)
							(mid -0.249642 0.249642)
							(end -0.1778 0.2794)
						)
						(arc
							(start 0.1778 0.2794)
							(mid 0.249642 0.249642)
							(end 0.2794 0.1778)
						)
						(arc
							(start 0.2794 -0.1778)
							(mid 0.249642 -0.249642)
							(end 0.1778 -0.2794)
						)
					)
					(width 0)
					(fill yes)
				)
			)
		)
	)
	(footprint ""
		(layer "F.Cu")
		(at 412.1277 -90.0938 180)
		(property "Reference" "R8E5"
			(at 0 0 180)
			(layer "F.SilkS")
			(hide yes)
			(effects
				(font
					(size 1.27 1.27)
				)
			)
		)
		(property "Value" ""
			(at 0 0 180)
			(layer "F.Fab")
			(effects
				(font
					(size 1.27 1.27)
				)
			)
		)
		(duplicate_pad_numbers_are_jumpers no)
		(fp_poly
			(pts
				(xy -0.2794 -0.1016) (xy 0.2794 -0.1016) (xy 0.2794 0.9906) (xy -0.2794 0.9906)
			)
			(stroke
				(width 0)
				(type default)
			)
			(fill no)
			(layer "F.CrtYd")
		)
		(fp_line
			(start 0.2794 0.9906)
			(end 0.2794 -0.1016)
			(stroke
				(width 0.1)
				(type default)
			)
			(layer "F.Fab")
		)
		(fp_line
			(start 0.2794 -0.1016)
			(end -0.2794 -0.1016)
			(stroke
				(width 0.1)
				(type default)
			)
			(layer "F.Fab")
		)
		(fp_line
			(start -0.2794 0.9906)
			(end 0.2794 0.9906)
			(stroke
				(width 0.1)
				(type default)
			)
			(layer "F.Fab")
		)
		(fp_line
			(start -0.2794 -0.1016)
			(end -0.2794 0.9906)
			(stroke
				(width 0.1)
				(type default)
			)
			(layer "F.Fab")
		)
		(pad "1" smd rect
			(at 0 0 180)
			(size 0.508 0.508)
			(layers "F.Cu" "F.Mask" "F.Paste")
			(net "FM_CTNR_PS_ON_R")
		)
		(pad "2" smd rect
			(at 0 0.889 180)
			(size 0.508 0.508)
			(layers "F.Cu" "F.Mask" "F.Paste")
			(net "FM_CTNR_PS_ON")
		)
		(zone
			(layer "F.Cu")
			(hatch none 0.5)
			(connect_pads
				(clearance 0)
			)
			(min_thickness 0.25)
			(keepout
				(tracks not_allowed)
				(vias allowed)
				(pads allowed)
				(copperpour not_allowed)
				(footprints allowed)
			)
			(placement
				(enabled no)
				(sheetname "")
			)
			(fill
				(thermal_gap 0.5)
				(thermal_bridge_width 0.5)
				(island_removal_mode 0)
			)
			(polygon
				(pts
					(xy 412.3817 -90.7288) (xy 411.8737 -90.7288) (xy 411.8737 -90.3478) (xy 412.3817 -90.3478)
				)
			)
		)
		(zone
			(layer "F.Cu")
			(hatch none 0.5)
			(connect_pads
				(clearance 0)
			)
			(min_thickness 0.25)
			(keepout
				(tracks allowed)
				(vias not_allowed)
				(pads allowed)
				(copperpour not_allowed)
				(footprints allowed)
			)
			(placement
				(enabled no)
				(sheetname "")
			)
			(fill
				(thermal_gap 0.5)
				(thermal_bridge_width 0.5)
				(island_removal_mode 0)
			)
			(polygon
				(pts
					(xy 412.3817 -90.3478) (xy 411.8737 -90.3478) (xy 411.8737 -90.7288) (xy 412.3817 -90.7288)
				)
			)
		)
	)
	(footprint ""
		(layer "F.Cu")
		(at 264.453624 -68.641214 -90)
		(property "Reference" "C5D55"
			(at 0 0 270)
			(layer "F.SilkS")
			(hide yes)
			(effects
				(font
					(size 1.27 1.27)
				)
			)
		)
		(property "Value" ""
			(at 0 0 270)
			(layer "F.Fab")
			(effects
				(font
					(size 1.27 1.27)
				)
			)
		)
		(duplicate_pad_numbers_are_jumpers no)
		(fp_poly
			(pts
				(xy -0.4953 -0.2032) (xy 0.4953 -0.2032) (xy 0.4953 1.6002) (xy -0.4953 1.6002)
			)
			(stroke
				(width 0)
				(type default)
			)
			(fill no)
			(layer "F.CrtYd")
		)
		(fp_line
			(start -0.4953 1.6002)
			(end -0.4953 -0.2032)
			(stroke
				(width 0.1)
				(type default)
			)
			(layer "F.Fab")
		)
		(fp_line
			(start 0.4953 1.6002)
			(end -0.4953 1.6002)
			(stroke
				(width 0.1)
				(type default)
			)
			(layer "F.Fab")
		)
		(fp_line
			(start -0.4953 -0.2032)
			(end 0.4953 -0.2032)
			(stroke
				(width 0.1)
				(type default)
			)
			(layer "F.Fab")
		)
		(fp_line
			(start 0.4953 -0.2032)
			(end 0.4953 1.6002)
			(stroke
				(width 0.1)
				(type default)
			)
			(layer "F.Fab")
		)
		(pad "1" smd rect
			(at 0 0 270)
			(size 0.762 0.889)
			(layers "F.Cu" "F.Mask" "F.Paste")
			(net "PVDDQ_ABC")
		)
		(pad "2" smd rect
			(at 0 1.397 270)
			(size 0.762 0.889)
			(layers "F.Cu" "F.Mask" "F.Paste")
			(net "GND")
		)
		(zone
			(layer "F.Cu")
			(hatch none 0.5)
			(connect_pads
				(clearance 0)
			)
			(min_thickness 0.25)
			(keepout
				(tracks not_allowed)
				(vias allowed)
				(pads allowed)
				(copperpour not_allowed)
				(footprints allowed)
			)
			(placement
				(enabled no)
				(sheetname "")
			)
			(fill
				(thermal_gap 0.5)
				(thermal_bridge_width 0.5)
				(island_removal_mode 0)
			)
			(polygon
				(pts
					(xy 264.009124 -69.022214) (xy 264.009124 -68.260214) (xy 263.501124 -68.260214) (xy 263.501124 -69.022214)
				)
			)
		)
	)
)
